(kicad_pcb
	(version 20260206)
	(generator "pcbnew")
	(generator_version "10.0")
	(general
		(thickness 1.6)
		(legacy_teardrops no)
	)
	(paper "A4")
	(title_block
		(title "peb — Lightning_PEB_BRD.brd")
		(comment 1 "Lightning (Wiwynn / Facebook NVMe JBOF) / footprints 2559-2563 of 2563")
	)
	(layers
		(0 "F.Cu" signal "TOP")
		(4 "In1.Cu" signal "L2GND")
		(6 "In2.Cu" signal "L3")
		(8 "In3.Cu" signal "L4VCC")
		(10 "In4.Cu" signal "L5VCC")
		(12 "In5.Cu" signal "L6")
		(14 "In6.Cu" signal "L7GND")
		(2 "B.Cu" signal "BOTTOM")
		(9 "F.Adhes" user "F.Adhesive")
		(11 "B.Adhes" user "B.Adhesive")
		(13 "F.Paste" user "Package Geometry/Pastemask Top")
		(15 "B.Paste" user "Package Geometry/Pastemask Bottom")
		(5 "F.SilkS" user "Ref Des/Silkscreen Top")
		(7 "B.SilkS" user "Ref Des/Silkscreen Bottom")
		(1 "F.Mask" user "Board Geometry/Soldermask Top")
		(3 "B.Mask" user "Board Geometry/Soldermask Bottom")
		(17 "Dwgs.User" user "User.Drawings")
		(19 "Cmts.User" user "User.Comments")
		(21 "Eco1.User" user "User.Eco1")
		(23 "Eco2.User" user "User.Eco2")
		(25 "Edge.Cuts" user "Board Geometry/Outline")
		(27 "Margin" user)
		(31 "F.CrtYd" user "Package Geometry/Place Bound Top")
		(29 "B.CrtYd" user "Package Geometry/Place Bound Bottom")
		(35 "F.Fab" user "Ref Des/Assembly Top")
		(33 "B.Fab" user "Ref Des/Assembly Bottom")
	)
	(footprint ""
		(layer "B.Cu")
		(at 129.2098 -200.3298 -90)
		(property "Reference" "R3206"
			(at 0 0 90)
			(layer "B.SilkS")
			(hide yes)
			(effects
				(font
					(size 1.27 1.27)
				)
				(justify mirror)
			)
		)
		(property "Value" "0R2J-2-GP"
			(at -0.064008 -3.993896 270)
			(unlocked yes)
			(layer "B.Fab")
			(hide yes)
			(effects
				(font
					(size 1.016 1.016)
					(thickness 0.1524)
				)
				(justify mirror)
			)
		)
		(property "Device Type" "R402H16"
			(at -0.064008 -5.517896 270)
			(unlocked yes)
			(layer "B.Fab")
			(hide yes)
			(effects
				(font
					(size 1.016 1.016)
					(thickness 0.1524)
				)
				(justify mirror)
			)
		)
		(duplicate_pad_numbers_are_jumpers no)
		(fp_line
			(start -0.508 -0.9398)
			(end 0.508 -0.9398)
			(stroke
				(width 0.1524)
				(type default)
			)
			(layer "B.SilkS")
		)
		(fp_line
			(start 0.508 -0.9398)
			(end 0.508 0.9398)
			(stroke
				(width 0.1524)
				(type default)
			)
			(layer "B.SilkS")
		)
		(fp_rect
			(start 0.508 0.9398)
			(end -0.508 -0.9398)
			(stroke
				(width 0)
				(type default)
			)
			(fill no)
			(layer "B.CrtYd")
		)
		(fp_rect
			(start 0.508 0.9398)
			(end -0.508 -0.9398)
			(stroke
				(width 0)
				(type default)
			)
			(fill no)
			(layer "B.Fab")
		)
		(pad "1" smd custom
			(at 0 -0.4445 90)
			(size 0.1397 0.1397)
			(layers "B.Cu" "B.Mask" "B.Paste")
			(net "SSD_PERST_Y1")
			(options
				(clearance outline)
				(anchor circle)
			)
			(primitives
				(gr_poly
					(pts
						(arc
							(start -0.1778 0.2794)
							(mid -0.249642 0.249642)
							(end -0.2794 0.1778)
						)
						(arc
							(start -0.2794 -0.1778)
							(mid -0.249642 -0.249642)
							(end -0.1778 -0.2794)
						)
						(arc
							(start 0.1778 -0.2794)
							(mid 0.249642 -0.249642)
							(end 0.2794 -0.1778)
						)
						(arc
							(start 0.2794 0.1778)
							(mid 0.249642 0.249642)
							(end 0.1778 0.2794)
						)
					)
					(width 0)
					(fill yes)
				)
			)
		)
		(pad "2" smd custom
			(at 0 0.4445 90)
			(size 0.1397 0.1397)
			(layers "B.Cu" "B.Mask" "B.Paste")
			(net "SSD_PERST#1_R")
			(options
				(clearance outline)
				(anchor circle)
			)
			(primitives
				(gr_poly
					(pts
						(arc
							(start -0.1778 0.2794)
							(mid -0.249642 0.249642)
							(end -0.2794 0.1778)
						)
						(arc
							(start -0.2794 -0.1778)
							(mid -0.249642 -0.249642)
							(end -0.1778 -0.2794)
						)
						(arc
							(start 0.1778 -0.2794)
							(mid 0.249642 -0.249642)
							(end 0.2794 -0.1778)
						)
						(arc
							(start 0.2794 0.1778)
							(mid 0.249642 0.249642)
							(end 0.1778 0.2794)
						)
					)
					(width 0)
					(fill yes)
				)
			)
		)
	)
	(footprint ""
		(layer "B.Cu")
		(at 231.3432 -35.0012 -90)
		(property "Reference" "C480"
			(at 0 0 90)
			(layer "B.SilkS")
			(hide yes)
			(effects
				(font
					(size 1.27 1.27)
				)
				(justify mirror)
			)
		)
		(property "Value" "SCD1U16V1KX-1-GP"
			(at 2.8321 -1.7399 270)
			(unlocked yes)
			(layer "B.Fab")
			(hide yes)
			(effects
				(font
					(size 1.016 1.016)
					(thickness 0.1524)
				)
				(justify mirror)
			)
		)
		(property "Device Type" "C0201H13"
			(at 2.8321 -3.2639 270)
			(unlocked yes)
			(layer "B.Fab")
			(hide yes)
			(effects
				(font
					(size 1.016 1.016)
					(thickness 0.1524)
				)
				(justify mirror)
			)
		)
		(duplicate_pad_numbers_are_jumpers no)
		(fp_rect
			(start 0.2794 0.6477)
			(end -0.2794 -0.6477)
			(stroke
				(width 0)
				(type default)
			)
			(fill no)
			(layer "B.CrtYd")
		)
		(fp_rect
			(start 0.2794 0.6477)
			(end -0.2794 -0.6477)
			(stroke
				(width 0)
				(type default)
			)
			(fill no)
			(layer "B.Fab")
		)
		(pad "1" smd custom
			(at 0 -0.2794 90)
			(size 0.0762 0.0762)
			(layers "B.Cu" "B.Mask" "B.Paste")
			(net "DUT_VDDO")
			(options
				(clearance outline)
				(anchor circle)
			)
			(primitives
				(gr_poly
					(pts
						(arc
							(start 0.1524 0.127)
							(mid 0.137521 0.162921)
							(end 0.1016 0.1778)
						)
						(arc
							(start -0.1016 0.1778)
							(mid -0.137521 0.162921)
							(end -0.1524 0.127)
						)
						(arc
							(start -0.1524 -0.127)
							(mid -0.137521 -0.162921)
							(end -0.1016 -0.1778)
						)
						(arc
							(start 0.1016 -0.1778)
							(mid 0.137521 -0.162921)
							(end 0.1524 -0.127)
						)
					)
					(width 0)
					(fill yes)
				)
			)
		)
		(pad "2" smd custom
			(at 0 0.2794 90)
			(size 0.0762 0.0762)
			(layers "B.Cu" "B.Mask" "B.Paste")
			(net "GND")
			(options
				(clearance outline)
				(anchor circle)
			)
			(primitives
				(gr_poly
					(pts
						(arc
							(start 0.1524 0.127)
							(mid 0.137521 0.162921)
							(end 0.1016 0.1778)
						)
						(arc
							(start -0.1016 0.1778)
							(mid -0.137521 0.162921)
							(end -0.1524 0.127)
						)
						(arc
							(start -0.1524 -0.127)
							(mid -0.137521 -0.162921)
							(end -0.1016 -0.1778)
						)
						(arc
							(start 0.1016 -0.1778)
							(mid 0.137521 -0.162921)
							(end 0.1524 -0.127)
						)
					)
					(width 0)
					(fill yes)
				)
			)
		)
	)
	(footprint ""
		(layer "B.Cu")
		(at 37.719 -132.969)
		(property "Reference" "C204"
			(at 0 0 0)
			(layer "B.SilkS")
			(hide yes)
			(effects
				(font
					(size 1.27 1.27)
				)
				(justify mirror)
			)
		)
		(property "Value" "SC1U10V2KX-4-GP"
			(at -1.1811 -2.7051 0)
			(unlocked yes)
			(layer "B.Fab")
			(hide yes)
			(effects
				(font
					(size 1.016 1.016)
					(thickness 0.1524)
				)
				(justify mirror)
			)
		)
		(property "Device Type" "C402H22"
			(at -1.1811 -4.2291 0)
			(unlocked yes)
			(layer "B.Fab")
			(hide yes)
			(effects
				(font
					(size 1.016 1.016)
					(thickness 0.1524)
				)
				(justify mirror)
			)
		)
		(duplicate_pad_numbers_are_jumpers no)
		(fp_rect
			(start 0.4318 0.9525)
			(end -0.4318 -0.9525)
			(stroke
				(width 0)
				(type default)
			)
			(fill no)
			(layer "B.CrtYd")
		)
		(fp_rect
			(start 0.4318 0.9525)
			(end -0.4318 -0.9525)
			(stroke
				(width 0)
				(type default)
			)
			(fill no)
			(layer "B.Fab")
		)
		(pad "1" smd custom
			(at 0 -0.4445 180)
			(size 0.1524 0.1524)
			(layers "B.Cu" "B.Mask" "B.Paste")
			(net "P1V26_STBY")
			(options
				(clearance outline)
				(anchor circle)
			)
			(primitives
				(gr_poly
					(pts
						(arc
							(start 0.3048 0.2032)
							(mid 0.275042 0.275042)
							(end 0.2032 0.3048)
						)
						(arc
							(start -0.2032 0.3048)
							(mid -0.275042 0.275042)
							(end -0.3048 0.2032)
						)
						(arc
							(start -0.3048 -0.2032)
							(mid -0.275042 -0.275042)
							(end -0.2032 -0.3048)
						)
						(arc
							(start 0.2032 -0.3048)
							(mid 0.275042 -0.275042)
							(end 0.3048 -0.2032)
						)
					)
					(width 0)
					(fill yes)
				)
			)
		)
		(pad "2" smd custom
			(at 0 0.4445 180)
			(size 0.1524 0.1524)
			(layers "B.Cu" "B.Mask" "B.Paste")
			(net "GND")
			(options
				(clearance outline)
				(anchor circle)
			)
			(primitives
				(gr_poly
					(pts
						(arc
							(start 0.3048 0.2032)
							(mid 0.275042 0.275042)
							(end 0.2032 0.3048)
						)
						(arc
							(start -0.2032 0.3048)
							(mid -0.275042 0.275042)
							(end -0.3048 0.2032)
						)
						(arc
							(start -0.3048 -0.2032)
							(mid -0.275042 -0.275042)
							(end -0.2032 -0.3048)
						)
						(arc
							(start 0.2032 -0.3048)
							(mid 0.275042 -0.275042)
							(end 0.3048 -0.2032)
						)
					)
					(width 0)
					(fill yes)
				)
			)
		)
	)
	(footprint ""
		(layer "B.Cu")
		(at 20.400518 -124.481844 90)
		(property "Reference" "R240"
			(at 0 0 90)
			(layer "B.SilkS")
			(hide yes)
			(effects
				(font
					(size 1.27 1.27)
				)
				(justify mirror)
			)
		)
		(property "Value" "0R2J-2-GP"
			(at -0.064008 -3.993896 90)
			(unlocked yes)
			(layer "B.Fab")
			(hide yes)
			(effects
				(font
					(size 1.016 1.016)
					(thickness 0.1524)
				)
				(justify mirror)
			)
		)
		(property "Device Type" "R402H16"
			(at -0.064008 -5.517896 90)
			(unlocked yes)
			(layer "B.Fab")
			(hide yes)
			(effects
				(font
					(size 1.016 1.016)
					(thickness 0.1524)
				)
				(justify mirror)
			)
		)
		(duplicate_pad_numbers_are_jumpers no)
		(fp_line
			(start 0.508 -0.9398)
			(end 0.508 0.9398)
			(stroke
				(width 0.1524)
				(type default)
			)
			(layer "B.SilkS")
		)
		(fp_line
			(start -0.508 -0.9398)
			(end 0.508 -0.9398)
			(stroke
				(width 0.1524)
				(type default)
			)
			(layer "B.SilkS")
		)
		(fp_rect
			(start 0.508 0.9398)
			(end -0.508 -0.9398)
			(stroke
				(width 0)
				(type default)
			)
			(fill no)
			(layer "B.CrtYd")
		)
		(fp_rect
			(start 0.508 0.9398)
			(end -0.508 -0.9398)
			(stroke
				(width 0)
				(type default)
			)
			(fill no)
			(layer "B.Fab")
		)
		(pad "1" smd custom
			(at 0 -0.4445 270)
			(size 0.1397 0.1397)
			(layers "B.Cu" "B.Mask" "B.Paste")
			(net "BMC_I2C2_MINI2_SCL_S")
			(options
				(clearance outline)
				(anchor circle)
			)
			(primitives
				(gr_poly
					(pts
						(arc
							(start -0.1778 0.2794)
							(mid -0.249642 0.249642)
							(end -0.2794 0.1778)
						)
						(arc
							(start -0.2794 -0.1778)
							(mid -0.249642 -0.249642)
							(end -0.1778 -0.2794)
						)
						(arc
							(start 0.1778 -0.2794)
							(mid 0.249642 -0.249642)
							(end 0.2794 -0.1778)
						)
						(arc
							(start 0.2794 0.1778)
							(mid 0.249642 0.249642)
							(end 0.1778 0.2794)
						)
					)
					(width 0)
					(fill yes)
				)
			)
		)
		(pad "2" smd custom
			(at 0 0.4445 270)
			(size 0.1397 0.1397)
			(layers "B.Cu" "B.Mask" "B.Paste")
			(net "BMC0_SMB2_CLK")
			(options
				(clearance outline)
				(anchor circle)
			)
			(primitives
				(gr_poly
					(pts
						(arc
							(start -0.1778 0.2794)
							(mid -0.249642 0.249642)
							(end -0.2794 0.1778)
						)
						(arc
							(start -0.2794 -0.1778)
							(mid -0.249642 -0.249642)
							(end -0.1778 -0.2794)
						)
						(arc
							(start 0.1778 -0.2794)
							(mid 0.249642 -0.249642)
							(end 0.2794 -0.1778)
						)
						(arc
							(start 0.2794 0.1778)
							(mid 0.249642 0.249642)
							(end 0.1778 0.2794)
						)
					)
					(width 0)
					(fill yes)
				)
			)
		)
	)
	(footprint ""
		(layer "B.Cu")
		(at 336.9818 -207.6196 90)
		(property "Reference" "C4160"
			(at 0 0 90)
			(layer "B.SilkS")
			(hide yes)
			(effects
				(font
					(size 1.27 1.27)
				)
				(justify mirror)
			)
		)
		(property "Value" "SCD1U25V3KX-GP"
			(at 0 -2.8194 90)
			(unlocked yes)
			(layer "B.Fab")
			(hide yes)
			(effects
				(font
					(size 1.016 1.016)
					(thickness 0.1524)
				)
				(justify mirror)
			)
		)
		(property "Device Type" "C603H36"
			(at 0 -4.3434 90)
			(unlocked yes)
			(layer "B.Fab")
			(hide yes)
			(effects
				(font
					(size 1.016 1.016)
					(thickness 0.1524)
				)
				(justify mirror)
			)
		)
		(duplicate_pad_numbers_are_jumpers no)
		(fp_line
			(start -0.508 0)
			(end 0.508 0)
			(stroke
				(width 0.2032)
				(type default)
			)
			(layer "B.SilkS")
		)
		(fp_rect
			(start 0.5842 1.3335)
			(end -0.5842 -1.3335)
			(stroke
				(width 0)
				(type default)
			)
			(fill no)
			(layer "B.CrtYd")
		)
		(fp_rect
			(start 0.5842 1.3335)
			(end -0.5842 -1.3335)
			(stroke
				(width 0)
				(type default)
			)
			(fill no)
			(layer "B.Fab")
		)
		(pad "1" smd custom
			(at 0 -0.762 270)
			(size 0.2159 0.2159)
			(layers "B.Cu" "B.Mask" "B.Paste")
			(net "GND")
			(options
				(clearance outline)
				(anchor circle)
			)
			(primitives
				(gr_poly
					(pts
						(arc
							(start -0.3302 0.4318)
							(mid -0.402042 0.402042)
							(end -0.4318 0.3302)
						)
						(arc
							(start -0.4318 -0.3302)
							(mid -0.402042 -0.402042)
							(end -0.3302 -0.4318)
						)
						(arc
							(start 0.3302 -0.4318)
							(mid 0.402042 -0.402042)
							(end 0.4318 -0.3302)
						)
						(arc
							(start 0.4318 0.3302)
							(mid 0.402042 0.402042)
							(end 0.3302 0.4318)
						)
					)
					(width 0)
					(fill yes)
				)
			)
		)
		(pad "2" smd custom
			(at 0 0.762 270)
			(size 0.2159 0.2159)
			(layers "B.Cu" "B.Mask" "B.Paste")
			(net "SSD_PWREN14_R")
			(options
				(clearance outline)
				(anchor circle)
			)
			(primitives
				(gr_poly
					(pts
						(arc
							(start -0.3302 0.4318)
							(mid -0.402042 0.402042)
							(end -0.4318 0.3302)
						)
						(arc
							(start -0.4318 -0.3302)
							(mid -0.402042 -0.402042)
							(end -0.3302 -0.4318)
						)
						(arc
							(start 0.3302 -0.4318)
							(mid 0.402042 -0.402042)
							(end 0.4318 -0.3302)
						)
						(arc
							(start 0.4318 0.3302)
							(mid 0.402042 0.402042)
							(end 0.3302 0.4318)
						)
					)
					(width 0)
					(fill yes)
				)
			)
		)
	)
)
